# T6G (Grand Teton) — schematic netlist excerpt (pin names and nets, part order shuffled) for the footprints in the layout excerpt that follows; sources: Cadence DE-HDL packaged netlist, KiCad conversion of 04192023_DAF0TMB3IC0_F0TG_MB_C_brd_V02_OCP.brd

R4159  Q_RES  100K 1% EMPTY  pkg 0402LF  page 124 : A = GPU_3V3IO_RSVD1 ; B = GND
R3279  Q_RES  68K 1% EMPTY  pkg 0402LF  page 111 : A = FM_P2E_EQB1 ; B = GND

(kicad_pcb
	(version 20260206)
	(generator "pcbnew")
	(generator_version "10.0")
	(general
		(thickness 1.6)
		(legacy_teardrops no)
	)
	(paper "A4")
	(title_block
		(title "04192023_DAF0TMB3IC0_F0TG_MB_C_brd_V02_OCP.brd")
		(comment 1 "Grand Teton / footprints 4186-4187 of 8354")
	)
	(layers
		(0 "F.Cu" signal "TOP")
		(4 "In1.Cu" signal "GND")
		(6 "In2.Cu" signal "IN1")
		(8 "In3.Cu" signal "GND1")
		(10 "In4.Cu" signal "IN2")
		(12 "In5.Cu" signal "GND2")
		(14 "In6.Cu" signal "IN3")
		(16 "In7.Cu" signal "GND3")
		(18 "In8.Cu" signal "VCC")
		(20 "In9.Cu" signal "VCC1")
		(22 "In10.Cu" signal "GND4")
		(24 "In11.Cu" signal "IN4")
		(26 "In12.Cu" signal "GND5")
		(28 "In13.Cu" signal "IN5")
		(30 "In14.Cu" signal "GND6")
		(32 "In15.Cu" signal "IN6")
		(34 "In16.Cu" signal "GND7")
		(2 "B.Cu" signal "BOTTOM")
		(9 "F.Adhes" user "F.Adhesive")
		(11 "B.Adhes" user "B.Adhesive")
		(13 "F.Paste" user "Package Geometry/Pastemask Top")
		(15 "B.Paste" user "Package Geometry/Pastemask Bottom")
		(5 "F.SilkS" user "Ref Des/Silkscreen Top")
		(7 "B.SilkS" user "Ref Des/Silkscreen Bottom")
		(1 "F.Mask" user "Board Geometry/Soldermask Top")
		(3 "B.Mask" user "Board Geometry/Soldermask Bottom")
		(17 "Dwgs.User" user "User.Drawings")
		(19 "Cmts.User" user "User.Comments")
		(21 "Eco1.User" user "User.Eco1")
		(23 "Eco2.User" user "User.Eco2")
		(25 "Edge.Cuts" user "Board Geometry/Outline")
		(27 "Margin" user)
		(31 "F.CrtYd" user "Package Geometry/Place Bound Top")
		(29 "B.CrtYd" user "Package Geometry/Place Bound Bottom")
		(35 "F.Fab" user "Ref Des/Assembly Top")
		(33 "B.Fab" user "Ref Des/Assembly Bottom")
	)
	(footprint ""
		(layer "F.Cu")
		(at 29.299662 -429.759364 90)
		(property "Reference" "R3279"
			(at 0 0 90)
			(layer "F.SilkS")
			(hide yes)
			(effects
				(font
					(size 1.27 1.27)
				)
			)
		)
		(property "Value" ""
			(at 0 0 90)
			(layer "F.Fab")
			(effects
				(font
					(size 1.27 1.27)
				)
			)
		)
		(duplicate_pad_numbers_are_jumpers no)
		(fp_line
			(start 0.7874 -0.4064)
			(end 0.7874 0.4064)
			(stroke
				(width 0.1524)
				(type default)
			)
			(layer "F.SilkS")
		)
		(fp_line
			(start -0.7874 -0.4064)
			(end 0.7874 -0.4064)
			(stroke
				(width 0.1524)
				(type default)
			)
			(layer "F.SilkS")
		)
		(fp_line
			(start 0.7874 0.4064)
			(end -0.7874 0.4064)
			(stroke
				(width 0.1524)
				(type default)
			)
			(layer "F.SilkS")
		)
		(fp_line
			(start -0.7874 0.4064)
			(end -0.7874 -0.4064)
			(stroke
				(width 0.1524)
				(type default)
			)
			(layer "F.SilkS")
		)
		(fp_line
			(start -0.12065 -0.305054)
			(end -0.12065 -0.2794)
			(stroke
				(width 0.1)
				(type default)
			)
			(layer "F.Fab")
		)
		(fp_line
			(start -0.67945 -0.305054)
			(end -0.12065 -0.305054)
			(stroke
				(width 0.1)
				(type default)
			)
			(layer "F.Fab")
		)
		(fp_line
			(start 0.67945 -0.3048)
			(end 0.67945 0.3048)
			(stroke
				(width 0.1)
				(type default)
			)
			(layer "F.Fab")
		)
		(fp_line
			(start 0.12065 -0.3048)
			(end 0.67945 -0.3048)
			(stroke
				(width 0.1)
				(type default)
			)
			(layer "F.Fab")
		)
		(fp_line
			(start 0.12065 -0.2794)
			(end 0.12065 -0.3048)
			(stroke
				(width 0.1)
				(type default)
			)
			(layer "F.Fab")
		)
		(fp_line
			(start -0.12065 -0.2794)
			(end 0.12065 -0.2794)
			(stroke
				(width 0.1)
				(type default)
			)
			(layer "F.Fab")
		)
		(fp_line
			(start 0.120396 0.2794)
			(end -0.12065 0.2794)
			(stroke
				(width 0.1)
				(type default)
			)
			(layer "F.Fab")
		)
		(fp_line
			(start -0.12065 0.2794)
			(end -0.12065 0.3048)
			(stroke
				(width 0.1)
				(type default)
			)
			(layer "F.Fab")
		)
		(fp_line
			(start 0.67945 0.3048)
			(end 0.120396 0.3048)
			(stroke
				(width 0.1)
				(type default)
			)
			(layer "F.Fab")
		)
		(fp_line
			(start 0.120396 0.3048)
			(end 0.120396 0.2794)
			(stroke
				(width 0.1)
				(type default)
			)
			(layer "F.Fab")
		)
		(fp_line
			(start -0.12065 0.3048)
			(end -0.67945 0.3048)
			(stroke
				(width 0.1)
				(type default)
			)
			(layer "F.Fab")
		)
		(fp_line
			(start -0.67945 0.3048)
			(end -0.67945 -0.305054)
			(stroke
				(width 0.1)
				(type default)
			)
			(layer "F.Fab")
		)
		(pad "1" smd circle
			(at -0.40005 0 90)
			(size 0 0)
			(layers "F.Cu" "F.Mask" "F.Paste")
			(net "FM_P2E_EQB1")
		)
		(pad "2" smd circle
			(at 0.40005 0 90)
			(size 0 0)
			(layers "F.Cu" "F.Mask" "F.Paste")
			(net "GND")
		)
	)
	(footprint ""
		(layer "F.Cu")
		(at 419.230302 -436.164736 90)
		(property "Reference" "R4159"
			(at 0 0 90)
			(layer "F.SilkS")
			(hide yes)
			(effects
				(font
					(size 1.27 1.27)
				)
			)
		)
		(property "Value" ""
			(at 0 0 90)
			(layer "F.Fab")
			(effects
				(font
					(size 1.27 1.27)
				)
			)
		)
		(duplicate_pad_numbers_are_jumpers no)
		(fp_line
			(start 0.7874 -0.4064)
			(end 0.7874 0.4064)
			(stroke
				(width 0.1524)
				(type default)
			)
			(layer "F.SilkS")
		)
		(fp_line
			(start -0.7874 -0.4064)
			(end 0.7874 -0.4064)
			(stroke
				(width 0.1524)
				(type default)
			)
			(layer "F.SilkS")
		)
		(fp_line
			(start 0.7874 0.4064)
			(end -0.7874 0.4064)
			(stroke
				(width 0.1524)
				(type default)
			)
			(layer "F.SilkS")
		)
		(fp_line
			(start -0.7874 0.4064)
			(end -0.7874 -0.4064)
			(stroke
				(width 0.1524)
				(type default)
			)
			(layer "F.SilkS")
		)
		(fp_line
			(start -0.12065 -0.305054)
			(end -0.12065 -0.2794)
			(stroke
				(width 0.1)
				(type default)
			)
			(layer "F.Fab")
		)
		(fp_line
			(start -0.67945 -0.305054)
			(end -0.12065 -0.305054)
			(stroke
				(width 0.1)
				(type default)
			)
			(layer "F.Fab")
		)
		(fp_line
			(start 0.67945 -0.3048)
			(end 0.67945 0.3048)
			(stroke
				(width 0.1)
				(type default)
			)
			(layer "F.Fab")
		)
		(fp_line
			(start 0.12065 -0.3048)
			(end 0.67945 -0.3048)
			(stroke
				(width 0.1)
				(type default)
			)
			(layer "F.Fab")
		)
		(fp_line
			(start 0.12065 -0.2794)
			(end 0.12065 -0.3048)
			(stroke
				(width 0.1)
				(type default)
			)
			(layer "F.Fab")
		)
		(fp_line
			(start -0.12065 -0.2794)
			(end 0.12065 -0.2794)
			(stroke
				(width 0.1)
				(type default)
			)
			(layer "F.Fab")
		)
		(fp_line
			(start 0.120396 0.2794)
			(end -0.12065 0.2794)
			(stroke
				(width 0.1)
				(type default)
			)
			(layer "F.Fab")
		)
		(fp_line
			(start -0.12065 0.2794)
			(end -0.12065 0.3048)
			(stroke
				(width 0.1)
				(type default)
			)
			(layer "F.Fab")
		)
		(fp_line
			(start 0.67945 0.3048)
			(end 0.120396 0.3048)
			(stroke
				(width 0.1)
				(type default)
			)
			(layer "F.Fab")
		)
		(fp_line
			(start 0.120396 0.3048)
			(end 0.120396 0.2794)
			(stroke
				(width 0.1)
				(type default)
			)
			(layer "F.Fab")
		)
		(fp_line
			(start -0.12065 0.3048)
			(end -0.67945 0.3048)
			(stroke
				(width 0.1)
				(type default)
			)
			(layer "F.Fab")
		)
		(fp_line
			(start -0.67945 0.3048)
			(end -0.67945 -0.305054)
			(stroke
				(width 0.1)
				(type default)
			)
			(layer "F.Fab")
		)
		(pad "1" smd circle
			(at -0.40005 0 90)
			(size 0 0)
			(layers "F.Cu" "F.Mask" "F.Paste")
			(net "GPU_3V3IO_RSVD1")
		)
		(pad "2" smd circle
			(at 0.40005 0 90)
			(size 0 0)
			(layers "F.Cu" "F.Mask" "F.Paste")
			(net "GND")
		)
	)
)
